# BASEBOARD_FAB2 (Tioga Pass) — schematic netlist excerpt (pin names and nets, part order shuffled) for the footprints in the layout excerpt that follows; sources: Cadence DE-HDL packaged netlist, KiCad conversion of Wiwynn_Tioga_Pass_MB.brd

RT46  RES  0 5.0% CHIP  pkg 0603  page 236 : A = VR_P1V05_PCH_STBY_PH1_BOOT ; B = VR_P1V05_PCH_STBY_PH1_BOOT_R
R8E38  RES  0.0 5% CHIP  pkg 0402  page 240 : A = VSENSE_RGND_P3V3_STBY ; B = AGND_P3V3_STBY
CT23  CAP  1000PF 50V 10% X7R  pkg 0402LF  page 207 : A = VR_PVCCIN_CPU1_PHASE1 ; B = VR_PVCCIN_CPU1_PHASE1_RC

(kicad_pcb
	(version 20260206)
	(generator "pcbnew")
	(generator_version "10.0")
	(general
		(thickness 1.6)
		(legacy_teardrops no)
	)
	(paper "A4")
	(title_block
		(title "Wiwynn_Tioga_Pass_MB.brd")
		(comment 1 "Tioga Pass / footprints 1159-1161 of 4770")
	)
	(layers
		(0 "F.Cu" signal "TOP")
		(4 "In1.Cu" signal "L2GND")
		(6 "In2.Cu" signal "L3")
		(8 "In3.Cu" signal "L4GND")
		(10 "In4.Cu" signal "L5")
		(12 "In5.Cu" signal "L6GND")
		(14 "In6.Cu" signal "L7VCC")
		(16 "In7.Cu" signal "L8VCC")
		(18 "In8.Cu" signal "L9GND")
		(20 "In9.Cu" signal "L10")
		(22 "In10.Cu" signal "L11GND")
		(24 "In11.Cu" signal "L12")
		(26 "In12.Cu" signal "L13GND")
		(2 "B.Cu" signal "BOTTOM")
		(9 "F.Adhes" user "F.Adhesive")
		(11 "B.Adhes" user "B.Adhesive")
		(13 "F.Paste" user "Package Geometry/Pastemask Top")
		(15 "B.Paste" user "Package Geometry/Pastemask Bottom")
		(5 "F.SilkS" user "Ref Des/Silkscreen Top")
		(7 "B.SilkS" user "Ref Des/Silkscreen Bottom")
		(1 "F.Mask" user "Board Geometry/Soldermask Top")
		(3 "B.Mask" user "Board Geometry/Soldermask Bottom")
		(17 "Dwgs.User" user "User.Drawings")
		(19 "Cmts.User" user "User.Comments")
		(21 "Eco1.User" user "User.Eco1")
		(23 "Eco2.User" user "User.Eco2")
		(25 "Edge.Cuts" user "Board Geometry/Outline")
		(27 "Margin" user)
		(31 "F.CrtYd" user "Package Geometry/Place Bound Top")
		(29 "B.CrtYd" user "Package Geometry/Place Bound Bottom")
		(35 "F.Fab" user "Ref Des/Assembly Top")
		(33 "B.Fab" user "Ref Des/Assembly Bottom")
	)
	(footprint ""
		(layer "F.Cu")
		(at 39.0906 -52.9082 -90)
		(property "Reference" "CT23"
			(at -0.8382 -0.67818 270)
			(unlocked yes)
			(layer "F.SilkS")
			(effects
				(font
					(size 0.4064 0.254)
					(thickness 0.1524)
				)
				(justify left)
			)
		)
		(property "Value" ""
			(at 0 0 270)
			(layer "F.Fab")
			(effects
				(font
					(size 1.27 1.27)
				)
			)
		)
		(duplicate_pad_numbers_are_jumpers no)
		(fp_poly
			(pts
				(xy 0.3048 -0.1016) (xy 0.3048 0.9906) (xy -0.3048 0.9906) (xy -0.3048 -0.1016)
			)
			(stroke
				(width 0)
				(type default)
			)
			(fill no)
			(layer "F.CrtYd")
		)
		(fp_line
			(start -0.3048 0.9906)
			(end 0.3048 0.9906)
			(stroke
				(width 0.1)
				(type default)
			)
			(layer "F.Fab")
		)
		(fp_line
			(start 0.3048 0.9906)
			(end 0.3048 -0.1016)
			(stroke
				(width 0.1)
				(type default)
			)
			(layer "F.Fab")
		)
		(fp_line
			(start -0.3048 -0.1016)
			(end -0.3048 0.9906)
			(stroke
				(width 0.1)
				(type default)
			)
			(layer "F.Fab")
		)
		(fp_line
			(start 0.3048 -0.1016)
			(end -0.3048 -0.1016)
			(stroke
				(width 0.1)
				(type default)
			)
			(layer "F.Fab")
		)
		(pad "1" smd rect
			(at 0 0 270)
			(size 0.508 0.508)
			(layers "F.Cu" "F.Mask" "F.Paste")
			(net "VR_PVCCIN_CPU1_PHASE1")
		)
		(pad "2" smd rect
			(at 0 0.889 270)
			(size 0.508 0.508)
			(layers "F.Cu" "F.Mask" "F.Paste")
			(net "VR_PVCCIN_CPU1_PHASE1_RC")
		)
		(zone
			(layer "F.Cu")
			(hatch none 0.5)
			(connect_pads
				(clearance 0)
			)
			(min_thickness 0.25)
			(keepout
				(tracks not_allowed)
				(vias allowed)
				(pads allowed)
				(copperpour not_allowed)
				(footprints allowed)
			)
			(placement
				(enabled no)
				(sheetname "")
			)
			(fill
				(thermal_gap 0.5)
				(thermal_bridge_width 0.5)
				(island_removal_mode 0)
			)
			(polygon
				(pts
					(xy 38.4556 -53.1622) (xy 38.4556 -52.6542) (xy 38.8366 -52.6542) (xy 38.8366 -53.1622)
				)
			)
		)
		(zone
			(layer "F.Cu")
			(hatch none 0.5)
			(connect_pads
				(clearance 0)
			)
			(min_thickness 0.25)
			(keepout
				(tracks allowed)
				(vias not_allowed)
				(pads allowed)
				(copperpour not_allowed)
				(footprints allowed)
			)
			(placement
				(enabled no)
				(sheetname "")
			)
			(fill
				(thermal_gap 0.5)
				(thermal_bridge_width 0.5)
				(island_removal_mode 0)
			)
			(polygon
				(pts
					(xy 38.8366 -53.1622) (xy 38.8366 -52.6542) (xy 38.4556 -52.6542) (xy 38.4556 -53.1622)
				)
			)
		)
	)
	(footprint ""
		(layer "F.Cu")
		(at 465.5947 -24.8539 -90)
		(property "Reference" "R8E38"
			(at 0 0 270)
			(layer "F.SilkS")
			(hide yes)
			(effects
				(font
					(size 1.27 1.27)
				)
			)
		)
		(property "Value" ""
			(at 0 0 270)
			(layer "F.Fab")
			(effects
				(font
					(size 1.27 1.27)
				)
			)
		)
		(duplicate_pad_numbers_are_jumpers no)
		(fp_rect
			(start 0.2794 0.9906)
			(end -0.2794 -0.1016)
			(stroke
				(width 0)
				(type default)
			)
			(fill no)
			(layer "F.CrtYd")
		)
		(fp_line
			(start -0.2794 0.9906)
			(end 0.2794 0.9906)
			(stroke
				(width 0.1)
				(type default)
			)
			(layer "F.Fab")
		)
		(fp_line
			(start 0.2794 0.9906)
			(end 0.2794 -0.1016)
			(stroke
				(width 0.1)
				(type default)
			)
			(layer "F.Fab")
		)
		(fp_line
			(start -0.2794 -0.1016)
			(end -0.2794 0.9906)
			(stroke
				(width 0.1)
				(type default)
			)
			(layer "F.Fab")
		)
		(fp_line
			(start 0.2794 -0.1016)
			(end -0.2794 -0.1016)
			(stroke
				(width 0.1)
				(type default)
			)
			(layer "F.Fab")
		)
		(pad "1" smd rect
			(at 0 0 270)
			(size 0.508 0.508)
			(layers "F.Cu" "F.Mask" "F.Paste")
			(net "VSENSE_RGND_P3V3_STBY")
		)
		(pad "2" smd rect
			(at 0 0.889 270)
			(size 0.508 0.508)
			(layers "F.Cu" "F.Mask" "F.Paste")
			(net "AGND_P3V3_STBY")
		)
		(zone
			(layer "F.Cu")
			(hatch none 0.5)
			(connect_pads
				(clearance 0)
			)
			(min_thickness 0.25)
			(keepout
				(tracks not_allowed)
				(vias allowed)
				(pads allowed)
				(copperpour not_allowed)
				(footprints allowed)
			)
			(placement
				(enabled no)
				(sheetname "")
			)
			(fill
				(thermal_gap 0.5)
				(thermal_bridge_width 0.5)
				(island_removal_mode 0)
			)
			(polygon
				(pts
					(xy 464.9597 -24.5999) (xy 465.3407 -24.5999) (xy 465.3407 -25.1079) (xy 464.9597 -25.1079)
				)
			)
		)
		(zone
			(layer "F.Cu")
			(hatch none 0.5)
			(connect_pads
				(clearance 0)
			)
			(min_thickness 0.25)
			(keepout
				(tracks allowed)
				(vias not_allowed)
				(pads allowed)
				(copperpour not_allowed)
				(footprints allowed)
			)
			(placement
				(enabled no)
				(sheetname "")
			)
			(fill
				(thermal_gap 0.5)
				(thermal_bridge_width 0.5)
				(island_removal_mode 0)
			)
			(polygon
				(pts
					(xy 464.9597 -24.5999) (xy 465.3407 -24.5999) (xy 465.3407 -25.1079) (xy 464.9597 -25.1079)
				)
			)
		)
	)
	(footprint ""
		(layer "F.Cu")
		(at 387.754876 -158.152084 -90)
		(property "Reference" "RT46"
			(at 1.01473 0.656336 180)
			(unlocked yes)
			(layer "F.SilkS")
			(effects
				(font
					(size 0.4064 0.254)
					(thickness 0.1524)
				)
			)
		)
		(property "Value" ""
			(at 0 0 270)
			(layer "F.Fab")
			(effects
				(font
					(size 1.27 1.27)
				)
			)
		)
		(duplicate_pad_numbers_are_jumpers no)
		(fp_poly
			(pts
				(xy -0.4953 -0.2032) (xy 0.4953 -0.2032) (xy 0.4953 1.6002) (xy -0.4953 1.6002)
			)
			(stroke
				(width 0)
				(type default)
			)
			(fill no)
			(layer "F.CrtYd")
		)
		(fp_line
			(start -0.4953 1.6002)
			(end -0.4953 -0.2032)
			(stroke
				(width 0.1)
				(type default)
			)
			(layer "F.Fab")
		)
		(fp_line
			(start 0.4953 1.6002)
			(end -0.4953 1.6002)
			(stroke
				(width 0.1)
				(type default)
			)
			(layer "F.Fab")
		)
		(fp_line
			(start -0.4953 -0.2032)
			(end 0.4953 -0.2032)
			(stroke
				(width 0.1)
				(type default)
			)
			(layer "F.Fab")
		)
		(fp_line
			(start 0.4953 -0.2032)
			(end 0.4953 1.6002)
			(stroke
				(width 0.1)
				(type default)
			)
			(layer "F.Fab")
		)
		(pad "1" smd rect
			(at 0 0 270)
			(size 0.762 0.889)
			(layers "F.Cu" "F.Mask" "F.Paste")
			(net "VR_P1V05_PCH_STBY_PH1_BOOT")
		)
		(pad "2" smd rect
			(at 0 1.397 270)
			(size 0.762 0.889)
			(layers "F.Cu" "F.Mask" "F.Paste")
			(net "VR_P1V05_PCH_STBY_PH1_BOOT_R")
		)
		(zone
			(layer "F.Cu")
			(hatch none 0.5)
			(connect_pads
				(clearance 0)
			)
			(min_thickness 0.25)
			(keepout
				(tracks not_allowed)
				(vias allowed)
				(pads allowed)
				(copperpour not_allowed)
				(footprints allowed)
			)
			(placement
				(enabled no)
				(sheetname "")
			)
			(fill
				(thermal_gap 0.5)
				(thermal_bridge_width 0.5)
				(island_removal_mode 0)
			)
			(polygon
				(pts
					(xy 386.802376 -158.533084) (xy 386.802376 -157.771084) (xy 387.310376 -157.771084) (xy 387.310376 -158.533084)
				)
			)
		)
		(zone
			(layer "F.Cu")
			(hatch none 0.5)
			(connect_pads
				(clearance 0)
			)
			(min_thickness 0.25)
			(keepout
				(tracks allowed)
				(vias not_allowed)
				(pads allowed)
				(copperpour not_allowed)
				(footprints allowed)
			)
			(placement
				(enabled no)
				(sheetname "")
			)
			(fill
				(thermal_gap 0.5)
				(thermal_bridge_width 0.5)
				(island_removal_mode 0)
			)
			(polygon
				(pts
					(xy 386.802376 -157.771084) (xy 387.310376 -157.771084) (xy 387.310376 -158.533084) (xy 386.802376 -158.533084)
				)
			)
		)
	)
)
